FILE_TYPE = MULTI_PHYS_TABLE;
PART 'CONN14_H54902001'
{====================================================================================================================================================================================================}
:PACK_TYPE | MATERIAL | PART_NUMBER     = EnvComp | PART_NUMBER  | JEDEC_TYPE             | DESCRIPTION                          | CLASS | COMPONENT_TYPE | HEIGHT     | LEAD_LENGTH  | SPEED_URL | Status |RPL| AML | Bus_Unit | Days ;
{====================================================================================================================================================================================================}
'THMT'     | 'CONN'   | 'H54902-001'(!) = ''      | 'H54902-001' | 'CONN14_H54902001'     | 'CONN_HDR,2X7,RCP,VT,2.00mm,9ST,NT'  | 'IO'  | 'THMT'         | '0.195 IN' | '0.117'      | 'http://speed.intel.com:8081/speed/module/pdm/item/pdm_item_detail_direct.asp?item_cde=H54902-001&item_rev=01&url_param=unused' | '' | '' | '' | '' | '' 
'THMT'     | 'EMPTY'  | 'H54902-001'(!) = ''      | 'H54902-001' | 'CONN14_H54902001'     | 'CONN_HDR,2X7,RCP,VT,2.00mm,9ST,NT'  | 'IO'  | 'THMT'         | '0.195 IN' | '0.117'      | 'http://speed.intel.com:8081/speed/module/pdm/item/pdm_item_detail_direct.asp?item_cde=H54902-001&item_rev=01&url_param=unused' | '' | '' | '' | '' | '' 
'PIP'      | 'CONN'   | 'H54902-001'(!) = ''      | 'H54902-001' | 'CONN14_H54902001_PIP' | 'CONN_HDR,2X7,RCP,VT,2.00mm,9ST,NT'  | 'IO'  | 'THMT'         | '0.195 IN' | '0.117'      | 'http://speed.intel.com:8081/speed/module/pdm/item/pdm_item_detail_direct.asp?item_cde=H54902-001&item_rev=01&url_param=unused' | '' | '' | '' | '' | '' 
'PIP'      | 'EMPTY'  | 'H54902-001'(!) = ''      | 'H54902-001' | 'CONN14_H54902001_PIP' | 'CONN_HDR,2X7,RCP,VT,2.00mm,9ST,NT'  | 'IO'  | 'THMT'         | '0.195 IN' | '0.117'      | 'http://speed.intel.com:8081/speed/module/pdm/item/pdm_item_detail_direct.asp?item_cde=H54902-001&item_rev=01&url_param=unused' | '' | '' | '' | '' | '' 
END_PART
END.
